# BASEBOARD_FAB2 (Tioga Pass) — schematic netlist excerpt (pin names and nets, part order shuffled) for the footprints in the layout excerpt that follows; sources: Cadence DE-HDL packaged netlist, KiCad conversion of Wiwynn_Tioga_Pass_MB.brd

C4B2  CAP  47UF 4V 20% X6S  pkg 0805  page 234 : A = PVPP_KLM ; B = GND
C1G8  CAP_A  0.01UF 25V 10% X7R  pkg 0402V  page 100 : A = M_H_CPU_VREF ; B = GND
C9F6  CAP  1000PF 50V 10% EMPTY  pkg 0402LF  page 239 : A = PWRGD_P2V5_BMC_STBY ; B = GND

(kicad_pcb
	(version 20260206)
	(generator "pcbnew")
	(generator_version "10.0")
	(general
		(thickness 1.6)
		(legacy_teardrops no)
	)
	(paper "A4")
	(title_block
		(title "Wiwynn_Tioga_Pass_MB.brd")
		(comment 1 "Tioga Pass / footprints 696-698 of 4770")
	)
	(layers
		(0 "F.Cu" signal "TOP")
		(4 "In1.Cu" signal "L2GND")
		(6 "In2.Cu" signal "L3")
		(8 "In3.Cu" signal "L4GND")
		(10 "In4.Cu" signal "L5")
		(12 "In5.Cu" signal "L6GND")
		(14 "In6.Cu" signal "L7VCC")
		(16 "In7.Cu" signal "L8VCC")
		(18 "In8.Cu" signal "L9GND")
		(20 "In9.Cu" signal "L10")
		(22 "In10.Cu" signal "L11GND")
		(24 "In11.Cu" signal "L12")
		(26 "In12.Cu" signal "L13GND")
		(2 "B.Cu" signal "BOTTOM")
		(9 "F.Adhes" user "F.Adhesive")
		(11 "B.Adhes" user "B.Adhesive")
		(13 "F.Paste" user "Package Geometry/Pastemask Top")
		(15 "B.Paste" user "Package Geometry/Pastemask Bottom")
		(5 "F.SilkS" user "Ref Des/Silkscreen Top")
		(7 "B.SilkS" user "Ref Des/Silkscreen Bottom")
		(1 "F.Mask" user "Board Geometry/Soldermask Top")
		(3 "B.Mask" user "Board Geometry/Soldermask Bottom")
		(17 "Dwgs.User" user "User.Drawings")
		(19 "Cmts.User" user "User.Comments")
		(21 "Eco1.User" user "User.Eco1")
		(23 "Eco2.User" user "User.Eco2")
		(25 "Edge.Cuts" user "Board Geometry/Outline")
		(27 "Margin" user)
		(31 "F.CrtYd" user "Package Geometry/Place Bound Top")
		(29 "B.CrtYd" user "Package Geometry/Place Bound Bottom")
		(35 "F.Fab" user "Ref Des/Assembly Top")
		(33 "B.Fab" user "Ref Des/Assembly Bottom")
	)
	(footprint ""
		(layer "F.Cu")
		(at 165.9763 -133.1976)
		(property "Reference" "C4B2"
			(at 0 0 0)
			(layer "F.SilkS")
			(hide yes)
			(effects
				(font
					(size 1.27 1.27)
				)
			)
		)
		(property "Value" ""
			(at 0 0 0)
			(layer "F.Fab")
			(effects
				(font
					(size 1.27 1.27)
				)
			)
		)
		(duplicate_pad_numbers_are_jumpers no)
		(fp_poly
			(pts
				(xy -0.7239 -0.2159) (xy 0.7239 -0.2159) (xy 0.7239 1.9939) (xy -0.7239 1.9939)
			)
			(stroke
				(width 0)
				(type default)
			)
			(fill no)
			(layer "F.CrtYd")
		)
		(fp_line
			(start -0.7239 -0.2159)
			(end -0.7239 1.9939)
			(stroke
				(width 0.1)
				(type default)
			)
			(layer "F.Fab")
		)
		(fp_line
			(start -0.7239 1.9939)
			(end 0.7239 1.9939)
			(stroke
				(width 0.1)
				(type default)
			)
			(layer "F.Fab")
		)
		(fp_line
			(start 0.7239 -0.2159)
			(end -0.7239 -0.2159)
			(stroke
				(width 0.1)
				(type default)
			)
			(layer "F.Fab")
		)
		(fp_line
			(start 0.7239 1.9939)
			(end 0.7239 -0.2159)
			(stroke
				(width 0.1)
				(type default)
			)
			(layer "F.Fab")
		)
		(pad "1" smd rect
			(at 0 0)
			(size 1.27 1.016)
			(layers "F.Cu" "F.Mask" "F.Paste")
			(net "PVPP_KLM")
		)
		(pad "2" smd rect
			(at 0 1.778)
			(size 1.27 1.016)
			(layers "F.Cu" "F.Mask" "F.Paste")
			(net "GND")
		)
		(zone
			(layer "F.Cu")
			(hatch none 0.5)
			(connect_pads
				(clearance 0)
			)
			(min_thickness 0.25)
			(keepout
				(tracks not_allowed)
				(vias allowed)
				(pads allowed)
				(copperpour not_allowed)
				(footprints allowed)
			)
			(placement
				(enabled no)
				(sheetname "")
			)
			(fill
				(thermal_gap 0.5)
				(thermal_bridge_width 0.5)
				(island_removal_mode 0)
			)
			(polygon
				(pts
					(xy 165.3413 -132.6896) (xy 166.6113 -132.6896) (xy 166.6113 -131.9276) (xy 165.3413 -131.9276)
				)
			)
		)
	)
	(footprint ""
		(layer "F.Cu")
		(at 471.5891 -43.0784 -90)
		(property "Reference" "C9F6"
			(at 0 0 270)
			(layer "F.SilkS")
			(hide yes)
			(effects
				(font
					(size 1.27 1.27)
				)
			)
		)
		(property "Value" ""
			(at 0 0 270)
			(layer "F.Fab")
			(effects
				(font
					(size 1.27 1.27)
				)
			)
		)
		(duplicate_pad_numbers_are_jumpers no)
		(fp_poly
			(pts
				(xy 0.3048 -0.1016) (xy 0.3048 0.9906) (xy -0.3048 0.9906) (xy -0.3048 -0.1016)
			)
			(stroke
				(width 0)
				(type default)
			)
			(fill no)
			(layer "F.CrtYd")
		)
		(fp_line
			(start -0.3048 0.9906)
			(end 0.3048 0.9906)
			(stroke
				(width 0.1)
				(type default)
			)
			(layer "F.Fab")
		)
		(fp_line
			(start 0.3048 0.9906)
			(end 0.3048 -0.1016)
			(stroke
				(width 0.1)
				(type default)
			)
			(layer "F.Fab")
		)
		(fp_line
			(start -0.3048 -0.1016)
			(end -0.3048 0.9906)
			(stroke
				(width 0.1)
				(type default)
			)
			(layer "F.Fab")
		)
		(fp_line
			(start 0.3048 -0.1016)
			(end -0.3048 -0.1016)
			(stroke
				(width 0.1)
				(type default)
			)
			(layer "F.Fab")
		)
		(pad "1" smd rect
			(at 0 0 270)
			(size 0.508 0.508)
			(layers "F.Cu" "F.Mask" "F.Paste")
			(net "PWRGD_P2V5_BMC_STBY")
		)
		(pad "2" smd rect
			(at 0 0.889 270)
			(size 0.508 0.508)
			(layers "F.Cu" "F.Mask" "F.Paste")
			(net "GND")
		)
		(zone
			(layer "F.Cu")
			(hatch none 0.5)
			(connect_pads
				(clearance 0)
			)
			(min_thickness 0.25)
			(keepout
				(tracks not_allowed)
				(vias allowed)
				(pads allowed)
				(copperpour not_allowed)
				(footprints allowed)
			)
			(placement
				(enabled no)
				(sheetname "")
			)
			(fill
				(thermal_gap 0.5)
				(thermal_bridge_width 0.5)
				(island_removal_mode 0)
			)
			(polygon
				(pts
					(xy 470.9541 -43.3324) (xy 470.9541 -42.8244) (xy 471.3351 -42.8244) (xy 471.3351 -43.3324)
				)
			)
		)
		(zone
			(layer "F.Cu")
			(hatch none 0.5)
			(connect_pads
				(clearance 0)
			)
			(min_thickness 0.25)
			(keepout
				(tracks allowed)
				(vias not_allowed)
				(pads allowed)
				(copperpour not_allowed)
				(footprints allowed)
			)
			(placement
				(enabled no)
				(sheetname "")
			)
			(fill
				(thermal_gap 0.5)
				(thermal_bridge_width 0.5)
				(island_removal_mode 0)
			)
			(polygon
				(pts
					(xy 471.3351 -43.3324) (xy 471.3351 -42.8244) (xy 470.9541 -42.8244) (xy 470.9541 -43.3324)
				)
			)
		)
	)
	(footprint ""
		(layer "F.Cu")
		(at 26.898092 -13.3985)
		(property "Reference" "C1G8"
			(at 0 0 0)
			(layer "F.SilkS")
			(hide yes)
			(effects
				(font
					(size 1.27 1.27)
				)
			)
		)
		(property "Value" ""
			(at 0 0 0)
			(layer "F.Fab")
			(effects
				(font
					(size 1.27 1.27)
				)
			)
		)
		(duplicate_pad_numbers_are_jumpers no)
		(fp_poly
			(pts
				(xy 0.3048 -0.1016) (xy 0.3048 0.9906) (xy -0.3048 0.9906) (xy -0.3048 -0.1016)
			)
			(stroke
				(width 0)
				(type default)
			)
			(fill no)
			(layer "F.CrtYd")
		)
		(fp_line
			(start -0.3048 -0.1016)
			(end -0.3048 0.9906)
			(stroke
				(width 0.1)
				(type default)
			)
			(layer "F.Fab")
		)
		(fp_line
			(start -0.3048 0.9906)
			(end 0.3048 0.9906)
			(stroke
				(width 0.1)
				(type default)
			)
			(layer "F.Fab")
		)
		(fp_line
			(start 0.3048 -0.1016)
			(end -0.3048 -0.1016)
			(stroke
				(width 0.1)
				(type default)
			)
			(layer "F.Fab")
		)
		(fp_line
			(start 0.3048 0.9906)
			(end 0.3048 -0.1016)
			(stroke
				(width 0.1)
				(type default)
			)
			(layer "F.Fab")
		)
		(pad "1" smd rect
			(at 0 0)
			(size 0.508 0.508)
			(layers "F.Cu" "F.Mask" "F.Paste")
			(net "M_H_CPU_VREF")
		)
		(pad "2" smd rect
			(at 0 0.889)
			(size 0.508 0.508)
			(layers "F.Cu" "F.Mask" "F.Paste")
			(net "GND")
		)
		(zone
			(layer "F.Cu")
			(hatch none 0.5)
			(connect_pads
				(clearance 0)
			)
			(min_thickness 0.25)
			(keepout
				(tracks allowed)
				(vias not_allowed)
				(pads allowed)
				(copperpour not_allowed)
				(footprints allowed)
			)
			(placement
				(enabled no)
				(sheetname "")
			)
			(fill
				(thermal_gap 0.5)
				(thermal_bridge_width 0.5)
				(island_removal_mode 0)
			)
			(polygon
				(pts
					(xy 26.644092 -13.1445) (xy 27.152092 -13.1445) (xy 27.152092 -12.7635) (xy 26.644092 -12.7635)
				)
			)
		)
		(zone
			(layer "F.Cu")
			(hatch none 0.5)
			(connect_pads
				(clearance 0)
			)
			(min_thickness 0.25)
			(keepout
				(tracks not_allowed)
				(vias allowed)
				(pads allowed)
				(copperpour not_allowed)
				(footprints allowed)
			)
			(placement
				(enabled no)
				(sheetname "")
			)
			(fill
				(thermal_gap 0.5)
				(thermal_bridge_width 0.5)
				(island_removal_mode 0)
			)
			(polygon
				(pts
					(xy 26.644092 -12.7635) (xy 27.152092 -12.7635) (xy 27.152092 -13.1445) (xy 26.644092 -13.1445)
				)
			)
		)
	)
)
